(kicad_pcb
	(version 20260206)
	(generator "pcbnew")
	(generator_version "10.0")
	(general
		(thickness 1.6)
		(legacy_teardrops no)
	)
	(paper "A4")
	(title_block
		(title "01162023_DA0F0TEBIF0_F0T_Expander_BD_F_brd_V02_OCP.brd")
		(comment 1 "Grand Teton / footprints 7864-7871 of 9728")
	)
	(layers
		(0 "F.Cu" signal "TOP")
		(4 "In1.Cu" signal "GND")
		(6 "In2.Cu" signal "VCC")
		(8 "In3.Cu" signal "VCC1")
		(10 "In4.Cu" signal "GND1")
		(12 "In5.Cu" signal "IN1")
		(14 "In6.Cu" signal "GND2")
		(16 "In7.Cu" signal "IN2")
		(18 "In8.Cu" signal "GND3")
		(20 "In9.Cu" signal "IN3")
		(22 "In10.Cu" signal "GND4")
		(24 "In11.Cu" signal "IN4")
		(26 "In12.Cu" signal "GND5")
		(28 "In13.Cu" signal "IN5")
		(30 "In14.Cu" signal "GND6")
		(32 "In15.Cu" signal "IN6")
		(34 "In16.Cu" signal "GND7")
		(2 "B.Cu" signal "BOTTOM")
		(9 "F.Adhes" user "F.Adhesive")
		(11 "B.Adhes" user "B.Adhesive")
		(13 "F.Paste" user "Package Geometry/Pastemask Top")
		(15 "B.Paste" user "Package Geometry/Pastemask Bottom")
		(5 "F.SilkS" user "Ref Des/Silkscreen Top")
		(7 "B.SilkS" user "Ref Des/Silkscreen Bottom")
		(1 "F.Mask" user "Board Geometry/Soldermask Top")
		(3 "B.Mask" user "Board Geometry/Soldermask Bottom")
		(17 "Dwgs.User" user "User.Drawings")
		(19 "Cmts.User" user "User.Comments")
		(21 "Eco1.User" user "User.Eco1")
		(23 "Eco2.User" user "User.Eco2")
		(25 "Edge.Cuts" user "Board Geometry/Outline")
		(27 "Margin" user)
		(31 "F.CrtYd" user "Package Geometry/Place Bound Top")
		(29 "B.CrtYd" user "Package Geometry/Place Bound Bottom")
		(35 "F.Fab" user "Ref Des/Assembly Top")
		(33 "B.Fab" user "Ref Des/Assembly Bottom")
	)
	(footprint ""
		(layer "B.Cu")
		(at 281.399742 -299.2755 180)
		(property "Reference" "C1634"
			(at 0 0 0)
			(layer "B.SilkS")
			(hide yes)
			(effects
				(font
					(size 1.27 1.27)
				)
				(justify mirror)
			)
		)
		(property "Value" ""
			(at 0 0 0)
			(layer "B.Fab")
			(effects
				(font
					(size 1.27 1.27)
				)
				(justify mirror)
			)
		)
		(duplicate_pad_numbers_are_jumpers no)
		(fp_line
			(start 0.299974 0.150114)
			(end 0.299974 -0.150114)
			(stroke
				(width 0.1)
				(type default)
			)
			(layer "B.Fab")
		)
		(fp_line
			(start 0.299974 -0.150114)
			(end -0.299974 -0.150114)
			(stroke
				(width 0.1)
				(type default)
			)
			(layer "B.Fab")
		)
		(fp_line
			(start -0.299974 0.150114)
			(end 0.299974 0.150114)
			(stroke
				(width 0.1)
				(type default)
			)
			(layer "B.Fab")
		)
		(fp_line
			(start -0.299974 -0.150114)
			(end -0.299974 0.150114)
			(stroke
				(width 0.1)
				(type default)
			)
			(layer "B.Fab")
		)
		(pad "1" smd rect
			(at 0.2667 0)
			(size 0.3048 0.381)
			(layers "B.Cu" "B.Mask" "B.Paste")
			(net "P0V8_PEX2")
		)
		(pad "2" smd rect
			(at -0.2667 0)
			(size 0.3048 0.381)
			(layers "B.Cu" "B.Mask" "B.Paste")
			(net "GND")
		)
	)
	(footprint ""
		(layer "B.Cu")
		(at 288.99993 -292.099746 90)
		(property "Reference" "C1726"
			(at 0 0 90)
			(layer "B.SilkS")
			(hide yes)
			(effects
				(font
					(size 1.27 1.27)
				)
				(justify mirror)
			)
		)
		(property "Value" ""
			(at 0 0 90)
			(layer "B.Fab")
			(effects
				(font
					(size 1.27 1.27)
				)
				(justify mirror)
			)
		)
		(duplicate_pad_numbers_are_jumpers no)
		(fp_line
			(start 0.299974 -0.150114)
			(end -0.299974 -0.150114)
			(stroke
				(width 0.1)
				(type default)
			)
			(layer "B.Fab")
		)
		(fp_line
			(start -0.299974 -0.150114)
			(end -0.299974 0.150114)
			(stroke
				(width 0.1)
				(type default)
			)
			(layer "B.Fab")
		)
		(fp_line
			(start 0.299974 0.150114)
			(end 0.299974 -0.150114)
			(stroke
				(width 0.1)
				(type default)
			)
			(layer "B.Fab")
		)
		(fp_line
			(start -0.299974 0.150114)
			(end 0.299974 0.150114)
			(stroke
				(width 0.1)
				(type default)
			)
			(layer "B.Fab")
		)
		(pad "1" smd rect
			(at 0.2667 0 270)
			(size 0.3048 0.381)
			(layers "B.Cu" "B.Mask" "B.Paste")
			(net "P0V8_SERDES_VDDA_PEX2")
		)
		(pad "2" smd rect
			(at -0.2667 0 270)
			(size 0.3048 0.381)
			(layers "B.Cu" "B.Mask" "B.Paste")
			(net "GND")
		)
	)
	(footprint ""
		(layer "B.Cu")
		(at 55.31993 -305.399948 -90)
		(property "Reference" "C2976"
			(at 0 0 90)
			(layer "B.SilkS")
			(hide yes)
			(effects
				(font
					(size 1.27 1.27)
				)
				(justify mirror)
			)
		)
		(property "Value" ""
			(at 0 0 90)
			(layer "B.Fab")
			(effects
				(font
					(size 1.27 1.27)
				)
				(justify mirror)
			)
		)
		(duplicate_pad_numbers_are_jumpers no)
		(fp_line
			(start -0.299974 0.150114)
			(end 0.299974 0.150114)
			(stroke
				(width 0.1)
				(type default)
			)
			(layer "B.Fab")
		)
		(fp_line
			(start 0.299974 0.150114)
			(end 0.299974 -0.150114)
			(stroke
				(width 0.1)
				(type default)
			)
			(layer "B.Fab")
		)
		(fp_line
			(start -0.299974 -0.150114)
			(end -0.299974 0.150114)
			(stroke
				(width 0.1)
				(type default)
			)
			(layer "B.Fab")
		)
		(fp_line
			(start 0.299974 -0.150114)
			(end -0.299974 -0.150114)
			(stroke
				(width 0.1)
				(type default)
			)
			(layer "B.Fab")
		)
		(pad "1" smd rect
			(at 0.2667 0 90)
			(size 0.3048 0.381)
			(layers "B.Cu" "B.Mask" "B.Paste")
			(net "P1V25_SERDES_VDDPLL_PEX0")
		)
		(pad "2" smd rect
			(at -0.2667 0 90)
			(size 0.3048 0.381)
			(layers "B.Cu" "B.Mask" "B.Paste")
			(net "GND")
		)
	)
	(footprint ""
		(layer "B.Cu")
		(at 251.830586 -195.26885)
		(property "Reference" "R5283"
			(at 0 0 0)
			(layer "B.SilkS")
			(hide yes)
			(effects
				(font
					(size 1.27 1.27)
				)
				(justify mirror)
			)
		)
		(property "Value" ""
			(at 0 0 0)
			(layer "B.Fab")
			(effects
				(font
					(size 1.27 1.27)
				)
				(justify mirror)
			)
		)
		(duplicate_pad_numbers_are_jumpers no)
		(fp_line
			(start -0.7874 -0.4064)
			(end -0.7874 0.4064)
			(stroke
				(width 0.1524)
				(type default)
			)
			(layer "B.SilkS")
		)
		(fp_line
			(start -0.7874 0.4064)
			(end 0.7874 0.4064)
			(stroke
				(width 0.1524)
				(type default)
			)
			(layer "B.SilkS")
		)
		(fp_line
			(start 0.7874 -0.4064)
			(end -0.7874 -0.4064)
			(stroke
				(width 0.1524)
				(type default)
			)
			(layer "B.SilkS")
		)
		(fp_line
			(start 0.7874 0.4064)
			(end 0.7874 -0.4064)
			(stroke
				(width 0.1524)
				(type default)
			)
			(layer "B.SilkS")
		)
		(fp_line
			(start -0.67945 -0.3048)
			(end -0.67945 0.3048)
			(stroke
				(width 0.1)
				(type default)
			)
			(layer "B.Fab")
		)
		(fp_line
			(start -0.67945 0.3048)
			(end -0.120396 0.3048)
			(stroke
				(width 0.1)
				(type default)
			)
			(layer "B.Fab")
		)
		(fp_line
			(start -0.12065 -0.3048)
			(end -0.67945 -0.3048)
			(stroke
				(width 0.1)
				(type default)
			)
			(layer "B.Fab")
		)
		(fp_line
			(start -0.12065 -0.2794)
			(end -0.12065 -0.3048)
			(stroke
				(width 0.1)
				(type default)
			)
			(layer "B.Fab")
		)
		(fp_line
			(start -0.120396 0.2794)
			(end 0.12065 0.2794)
			(stroke
				(width 0.1)
				(type default)
			)
			(layer "B.Fab")
		)
		(fp_line
			(start -0.120396 0.3048)
			(end -0.120396 0.2794)
			(stroke
				(width 0.1)
				(type default)
			)
			(layer "B.Fab")
		)
		(fp_line
			(start 0.12065 -0.305054)
			(end 0.12065 -0.2794)
			(stroke
				(width 0.1)
				(type default)
			)
			(layer "B.Fab")
		)
		(fp_line
			(start 0.12065 -0.2794)
			(end -0.12065 -0.2794)
			(stroke
				(width 0.1)
				(type default)
			)
			(layer "B.Fab")
		)
		(fp_line
			(start 0.12065 0.2794)
			(end 0.12065 0.3048)
			(stroke
				(width 0.1)
				(type default)
			)
			(layer "B.Fab")
		)
		(fp_line
			(start 0.12065 0.3048)
			(end 0.67945 0.3048)
			(stroke
				(width 0.1)
				(type default)
			)
			(layer "B.Fab")
		)
		(fp_line
			(start 0.67945 -0.305054)
			(end 0.12065 -0.305054)
			(stroke
				(width 0.1)
				(type default)
			)
			(layer "B.Fab")
		)
		(fp_line
			(start 0.67945 0.3048)
			(end 0.67945 -0.305054)
			(stroke
				(width 0.1)
				(type default)
			)
			(layer "B.Fab")
		)
		(pad "1" smd circle
			(at 0.40005 0 180)
			(size 0 0)
			(layers "B.Cu" "B.Mask" "B.Paste")
			(net "P3V3_AUX")
		)
		(pad "2" smd circle
			(at -0.40005 0 180)
			(size 0 0)
			(layers "B.Cu" "B.Mask" "B.Paste")
			(net "JTAG_BIC_TCK_R")
		)
	)
	(footprint ""
		(layer "B.Cu")
		(at 229.715822 -143.815054 -90)
		(property "Reference" "C2795"
			(at 0 0 90)
			(layer "B.SilkS")
			(hide yes)
			(effects
				(font
					(size 1.27 1.27)
				)
				(justify mirror)
			)
		)
		(property "Value" ""
			(at 0 0 90)
			(layer "B.Fab")
			(effects
				(font
					(size 1.27 1.27)
				)
				(justify mirror)
			)
		)
		(duplicate_pad_numbers_are_jumpers no)
		(fp_line
			(start -0.7874 0.4064)
			(end 0.7874 0.4064)
			(stroke
				(width 0.1524)
				(type default)
			)
			(layer "B.SilkS")
		)
		(fp_line
			(start 0.7874 0.4064)
			(end 0.7874 -0.4064)
			(stroke
				(width 0.1524)
				(type default)
			)
			(layer "B.SilkS")
		)
		(fp_line
			(start -0.7874 -0.4064)
			(end -0.7874 0.4064)
			(stroke
				(width 0.1524)
				(type default)
			)
			(layer "B.SilkS")
		)
		(fp_line
			(start 0.7874 -0.4064)
			(end -0.7874 -0.4064)
			(stroke
				(width 0.1524)
				(type default)
			)
			(layer "B.SilkS")
		)
		(fp_line
			(start -0.67945 0.3048)
			(end -0.120396 0.3048)
			(stroke
				(width 0.1)
				(type default)
			)
			(layer "B.Fab")
		)
		(fp_line
			(start -0.120396 0.3048)
			(end -0.120396 0.2794)
			(stroke
				(width 0.1)
				(type default)
			)
			(layer "B.Fab")
		)
		(fp_line
			(start 0.12065 0.3048)
			(end 0.67945 0.3048)
			(stroke
				(width 0.1)
				(type default)
			)
			(layer "B.Fab")
		)
		(fp_line
			(start 0.67945 0.3048)
			(end 0.67945 -0.305054)
			(stroke
				(width 0.1)
				(type default)
			)
			(layer "B.Fab")
		)
		(fp_line
			(start -0.120396 0.2794)
			(end 0.12065 0.2794)
			(stroke
				(width 0.1)
				(type default)
			)
			(layer "B.Fab")
		)
		(fp_line
			(start 0.12065 0.2794)
			(end 0.12065 0.3048)
			(stroke
				(width 0.1)
				(type default)
			)
			(layer "B.Fab")
		)
		(fp_line
			(start -0.12065 -0.2794)
			(end -0.12065 -0.3048)
			(stroke
				(width 0.1)
				(type default)
			)
			(layer "B.Fab")
		)
		(fp_line
			(start 0.12065 -0.2794)
			(end -0.12065 -0.2794)
			(stroke
				(width 0.1)
				(type default)
			)
			(layer "B.Fab")
		)
		(fp_line
			(start -0.67945 -0.3048)
			(end -0.67945 0.3048)
			(stroke
				(width 0.1)
				(type default)
			)
			(layer "B.Fab")
		)
		(fp_line
			(start -0.12065 -0.3048)
			(end -0.67945 -0.3048)
			(stroke
				(width 0.1)
				(type default)
			)
			(layer "B.Fab")
		)
		(fp_line
			(start 0.12065 -0.305054)
			(end 0.12065 -0.2794)
			(stroke
				(width 0.1)
				(type default)
			)
			(layer "B.Fab")
		)
		(fp_line
			(start 0.67945 -0.305054)
			(end 0.12065 -0.305054)
			(stroke
				(width 0.1)
				(type default)
			)
			(layer "B.Fab")
		)
		(pad "1" smd circle
			(at 0.40005 0 90)
			(size 0 0)
			(layers "B.Cu" "B.Mask" "B.Paste")
			(net "P3V3_CLK_GEN_VDDXTAL_CK440_PEX")
		)
		(pad "2" smd circle
			(at -0.40005 0 90)
			(size 0 0)
			(layers "B.Cu" "B.Mask" "B.Paste")
			(net "GND")
		)
	)
	(footprint ""
		(layer "B.Cu")
		(at 331.183996 -215.05418 180)
		(property "Reference" "R5639"
			(at 0 0 0)
			(layer "B.SilkS")
			(hide yes)
			(effects
				(font
					(size 1.27 1.27)
				)
				(justify mirror)
			)
		)
		(property "Value" ""
			(at 0 0 0)
			(layer "B.Fab")
			(effects
				(font
					(size 1.27 1.27)
				)
				(justify mirror)
			)
		)
		(duplicate_pad_numbers_are_jumpers no)
		(fp_line
			(start 1.2954 0.5842)
			(end 1.2954 -0.5842)
			(stroke
				(width 0.1524)
				(type default)
			)
			(layer "B.SilkS")
		)
		(fp_line
			(start 1.2954 -0.5842)
			(end -1.2954 -0.5842)
			(stroke
				(width 0.1524)
				(type default)
			)
			(layer "B.SilkS")
		)
		(fp_line
			(start -1.2954 0.5842)
			(end 1.2954 0.5842)
			(stroke
				(width 0.1524)
				(type default)
			)
			(layer "B.SilkS")
		)
		(fp_line
			(start -1.2954 -0.5842)
			(end -1.2954 0.5842)
			(stroke
				(width 0.1524)
				(type default)
			)
			(layer "B.SilkS")
		)
		(fp_line
			(start 1.1938 0.4064)
			(end 1.1938 -0.406654)
			(stroke
				(width 0.1)
				(type default)
			)
			(layer "B.Fab")
		)
		(fp_line
			(start 1.1938 -0.406654)
			(end 0.8636 -0.406654)
			(stroke
				(width 0.1)
				(type default)
			)
			(layer "B.Fab")
		)
		(fp_line
			(start 0.8636 0.4572)
			(end 0.8636 0.4318)
			(stroke
				(width 0.1)
				(type default)
			)
			(layer "B.Fab")
		)
		(fp_line
			(start 0.8636 0.4318)
			(end 0.8636 0.4064)
			(stroke
				(width 0.1)
				(type default)
			)
			(layer "B.Fab")
		)
		(fp_line
			(start 0.8636 0.4064)
			(end 1.1938 0.4064)
			(stroke
				(width 0.1)
				(type default)
			)
			(layer "B.Fab")
		)
		(fp_line
			(start 0.8636 -0.406654)
			(end 0.8636 -0.4572)
			(stroke
				(width 0.1)
				(type default)
			)
			(layer "B.Fab")
		)
		(fp_line
			(start 0.8636 -0.4572)
			(end -0.8636 -0.4572)
			(stroke
				(width 0.1)
				(type default)
			)
			(layer "B.Fab")
		)
		(fp_line
			(start -0.8636 0.4572)
			(end 0.8636 0.4572)
			(stroke
				(width 0.1)
				(type default)
			)
			(layer "B.Fab")
		)
		(fp_line
			(start -0.8636 0.4064)
			(end -0.8636 0.4572)
			(stroke
				(width 0.1)
				(type default)
			)
			(layer "B.Fab")
		)
		(fp_line
			(start -0.8636 -0.406654)
			(end -1.1938 -0.406654)
			(stroke
				(width 0.1)
				(type default)
			)
			(layer "B.Fab")
		)
		(fp_line
			(start -0.8636 -0.4572)
			(end -0.8636 -0.406654)
			(stroke
				(width 0.1)
				(type default)
			)
			(layer "B.Fab")
		)
		(fp_line
			(start -1.1938 0.4064)
			(end -0.8636 0.4064)
			(stroke
				(width 0.1)
				(type default)
			)
			(layer "B.Fab")
		)
		(fp_line
			(start -1.1938 -0.406654)
			(end -1.1938 0.4064)
			(stroke
				(width 0.1)
				(type default)
			)
			(layer "B.Fab")
		)
		(pad "1" smd rect
			(at 0.7366 0 90)
			(size 0.7112 0.8128)
			(layers "B.Cu" "B.Mask" "B.Paste")
			(net "P3V3_AUX")
		)
		(pad "2" smd rect
			(at -0.7366 0 90)
			(size 0.7112 0.8128)
			(layers "B.Cu" "B.Mask" "B.Paste")
			(net "P3V3_FPGA_VCCIO3")
		)
	)
	(footprint ""
		(layer "B.Cu")
		(at 175.749966 -301.599854 -90)
		(property "Reference" "C1470"
			(at 0 0 90)
			(layer "B.SilkS")
			(hide yes)
			(effects
				(font
					(size 1.27 1.27)
				)
				(justify mirror)
			)
		)
		(property "Value" ""
			(at 0 0 90)
			(layer "B.Fab")
			(effects
				(font
					(size 1.27 1.27)
				)
				(justify mirror)
			)
		)
		(duplicate_pad_numbers_are_jumpers no)
		(fp_line
			(start -0.299974 0.150114)
			(end 0.299974 0.150114)
			(stroke
				(width 0.1)
				(type default)
			)
			(layer "B.Fab")
		)
		(fp_line
			(start 0.299974 0.150114)
			(end 0.299974 -0.150114)
			(stroke
				(width 0.1)
				(type default)
			)
			(layer "B.Fab")
		)
		(fp_line
			(start -0.299974 -0.150114)
			(end -0.299974 0.150114)
			(stroke
				(width 0.1)
				(type default)
			)
			(layer "B.Fab")
		)
		(fp_line
			(start 0.299974 -0.150114)
			(end -0.299974 -0.150114)
			(stroke
				(width 0.1)
				(type default)
			)
			(layer "B.Fab")
		)
		(pad "1" smd rect
			(at 0.2667 0 90)
			(size 0.3048 0.381)
			(layers "B.Cu" "B.Mask" "B.Paste")
			(net "P0V8_SERDES_VDDA_PEX1")
		)
		(pad "2" smd rect
			(at -0.2667 0 90)
			(size 0.3048 0.381)
			(layers "B.Cu" "B.Mask" "B.Paste")
			(net "GND")
		)
	)
	(footprint ""
		(layer "B.Cu")
		(at 226.19716 -266.794996 180)
		(property "Reference" "L98"
			(at 0 0 0)
			(layer "B.SilkS")
			(hide yes)
			(effects
				(font
					(size 1.27 1.27)
				)
				(justify mirror)
			)
		)
		(property "Value" ""
			(at 0 0 0)
			(layer "B.Fab")
			(effects
				(font
					(size 1.27 1.27)
				)
				(justify mirror)
			)
		)
		(duplicate_pad_numbers_are_jumpers no)
		(fp_line
			(start 2.248154 4.9911)
			(end -2.248154 4.9911)
			(stroke
				(width 0.1524)
				(type default)
			)
			(layer "B.SilkS")
		)
		(fp_line
			(start 2.248154 1.768094)
			(end 2.248154 4.9911)
			(stroke
				(width 0.1524)
				(type default)
			)
			(layer "B.SilkS")
		)
		(fp_line
			(start 2.248154 -4.9911)
			(end 2.248154 -2.036064)
			(stroke
				(width 0.1524)
				(type default)
			)
			(layer "B.SilkS")
		)
		(fp_line
			(start -2.248154 4.9911)
			(end -2.248154 1.768094)
			(stroke
				(width 0.1524)
				(type default)
			)
			(layer "B.SilkS")
		)
		(fp_line
			(start -2.248154 -2.036064)
			(end -2.248154 -4.9911)
			(stroke
				(width 0.1524)
				(type default)
			)
			(layer "B.SilkS")
		)
		(fp_line
			(start -2.248154 -4.9911)
			(end 2.248154 -4.9911)
			(stroke
				(width 0.1524)
				(type default)
			)
			(layer "B.SilkS")
		)
		(fp_line
			(start 1.700022 0.899922)
			(end -1.700022 0.899922)
			(stroke
				(width 0.1)
				(type default)
			)
			(layer "B.Fab")
		)
		(fp_line
			(start 1.700022 -0.899922)
			(end 1.700022 0.899922)
			(stroke
				(width 0.1)
				(type default)
			)
			(layer "B.Fab")
		)
		(fp_line
			(start -1.700022 0.899922)
			(end -1.700022 -0.899922)
			(stroke
				(width 0.1)
				(type default)
			)
			(layer "B.Fab")
		)
		(fp_line
			(start -1.700022 -0.899922)
			(end 1.700022 -0.899922)
			(stroke
				(width 0.1)
				(type default)
			)
			(layer "B.Fab")
		)
		(pad "1" smd rect
			(at 1.575054 0)
			(size 1.1684 9.8044)
			(layers "B.Cu" "B.Mask" "B.Paste")
			(net "P1V25_PEX1")
		)
		(pad "2" smd rect
			(at -1.575054 0)
			(size 1.1684 9.8044)
			(layers "B.Cu" "B.Mask" "B.Paste")
			(net "P1V25_SERDES_VDDPLL_PEX1")
		)
	)
)
